# T6G (Grand Teton) — schematic netlist excerpt (pin names and nets, part order shuffled) for the footprints in the layout excerpt that follows; sources: Cadence DE-HDL packaged netlist, KiCad conversion of 04192023_DAF0TMB3IC0_F0TG_MB_C_brd_V02_OCP.brd

R2985  Q_RES  2.2K 5% CHIP  pkg 0402LF  page 250 : A = P3V3_AUX ; B = SMB_BMC_SWB_SDA
PR3912  Q_RES  120K 1% CHIP  pkg 0402LF  page 263 : A = AGND_HSC ; B = HSC_MODE_2

(kicad_pcb
	(version 20260206)
	(generator "pcbnew")
	(generator_version "10.0")
	(general
		(thickness 1.6)
		(legacy_teardrops no)
	)
	(paper "A4")
	(title_block
		(title "04192023_DAF0TMB3IC0_F0TG_MB_C_brd_V02_OCP.brd")
		(comment 1 "Grand Teton / footprints 4192-4193 of 8354")
	)
	(layers
		(0 "F.Cu" signal "TOP")
		(4 "In1.Cu" signal "GND")
		(6 "In2.Cu" signal "IN1")
		(8 "In3.Cu" signal "GND1")
		(10 "In4.Cu" signal "IN2")
		(12 "In5.Cu" signal "GND2")
		(14 "In6.Cu" signal "IN3")
		(16 "In7.Cu" signal "GND3")
		(18 "In8.Cu" signal "VCC")
		(20 "In9.Cu" signal "VCC1")
		(22 "In10.Cu" signal "GND4")
		(24 "In11.Cu" signal "IN4")
		(26 "In12.Cu" signal "GND5")
		(28 "In13.Cu" signal "IN5")
		(30 "In14.Cu" signal "GND6")
		(32 "In15.Cu" signal "IN6")
		(34 "In16.Cu" signal "GND7")
		(2 "B.Cu" signal "BOTTOM")
		(9 "F.Adhes" user "F.Adhesive")
		(11 "B.Adhes" user "B.Adhesive")
		(13 "F.Paste" user "Package Geometry/Pastemask Top")
		(15 "B.Paste" user "Package Geometry/Pastemask Bottom")
		(5 "F.SilkS" user "Ref Des/Silkscreen Top")
		(7 "B.SilkS" user "Ref Des/Silkscreen Bottom")
		(1 "F.Mask" user "Board Geometry/Soldermask Top")
		(3 "B.Mask" user "Board Geometry/Soldermask Bottom")
		(17 "Dwgs.User" user "User.Drawings")
		(19 "Cmts.User" user "User.Comments")
		(21 "Eco1.User" user "User.Eco1")
		(23 "Eco2.User" user "User.Eco2")
		(25 "Edge.Cuts" user "Board Geometry/Outline")
		(27 "Margin" user)
		(31 "F.CrtYd" user "Package Geometry/Place Bound Top")
		(29 "B.CrtYd" user "Package Geometry/Place Bound Bottom")
		(35 "F.Fab" user "Ref Des/Assembly Top")
		(33 "B.Fab" user "Ref Des/Assembly Bottom")
	)
	(footprint ""
		(layer "F.Cu")
		(at 215.4301 -407.068782 180)
		(property "Reference" "PR3912"
			(at 0 0 180)
			(layer "F.SilkS")
			(hide yes)
			(effects
				(font
					(size 1.27 1.27)
				)
			)
		)
		(property "Value" ""
			(at 0 0 180)
			(layer "F.Fab")
			(effects
				(font
					(size 1.27 1.27)
				)
			)
		)
		(duplicate_pad_numbers_are_jumpers no)
		(fp_line
			(start 0.7874 0.4064)
			(end -0.7874 0.4064)
			(stroke
				(width 0.1524)
				(type default)
			)
			(layer "F.SilkS")
		)
		(fp_line
			(start 0.7874 -0.4064)
			(end 0.7874 0.4064)
			(stroke
				(width 0.1524)
				(type default)
			)
			(layer "F.SilkS")
		)
		(fp_line
			(start -0.7874 0.4064)
			(end -0.7874 -0.4064)
			(stroke
				(width 0.1524)
				(type default)
			)
			(layer "F.SilkS")
		)
		(fp_line
			(start -0.7874 -0.4064)
			(end 0.7874 -0.4064)
			(stroke
				(width 0.1524)
				(type default)
			)
			(layer "F.SilkS")
		)
		(fp_line
			(start 0.67945 0.3048)
			(end 0.120396 0.3048)
			(stroke
				(width 0.1)
				(type default)
			)
			(layer "F.Fab")
		)
		(fp_line
			(start 0.67945 -0.3048)
			(end 0.67945 0.3048)
			(stroke
				(width 0.1)
				(type default)
			)
			(layer "F.Fab")
		)
		(fp_line
			(start 0.12065 -0.2794)
			(end 0.12065 -0.3048)
			(stroke
				(width 0.1)
				(type default)
			)
			(layer "F.Fab")
		)
		(fp_line
			(start 0.12065 -0.3048)
			(end 0.67945 -0.3048)
			(stroke
				(width 0.1)
				(type default)
			)
			(layer "F.Fab")
		)
		(fp_line
			(start 0.120396 0.3048)
			(end 0.120396 0.2794)
			(stroke
				(width 0.1)
				(type default)
			)
			(layer "F.Fab")
		)
		(fp_line
			(start 0.120396 0.2794)
			(end -0.12065 0.2794)
			(stroke
				(width 0.1)
				(type default)
			)
			(layer "F.Fab")
		)
		(fp_line
			(start -0.12065 0.3048)
			(end -0.67945 0.3048)
			(stroke
				(width 0.1)
				(type default)
			)
			(layer "F.Fab")
		)
		(fp_line
			(start -0.12065 0.2794)
			(end -0.12065 0.3048)
			(stroke
				(width 0.1)
				(type default)
			)
			(layer "F.Fab")
		)
		(fp_line
			(start -0.12065 -0.2794)
			(end 0.12065 -0.2794)
			(stroke
				(width 0.1)
				(type default)
			)
			(layer "F.Fab")
		)
		(fp_line
			(start -0.12065 -0.305054)
			(end -0.12065 -0.2794)
			(stroke
				(width 0.1)
				(type default)
			)
			(layer "F.Fab")
		)
		(fp_line
			(start -0.67945 0.3048)
			(end -0.67945 -0.305054)
			(stroke
				(width 0.1)
				(type default)
			)
			(layer "F.Fab")
		)
		(fp_line
			(start -0.67945 -0.305054)
			(end -0.12065 -0.305054)
			(stroke
				(width 0.1)
				(type default)
			)
			(layer "F.Fab")
		)
		(pad "1" smd circle
			(at -0.40005 0 180)
			(size 0 0)
			(layers "F.Cu" "F.Mask" "F.Paste")
			(net "AGND_HSC")
		)
		(pad "2" smd circle
			(at 0.40005 0 180)
			(size 0 0)
			(layers "F.Cu" "F.Mask" "F.Paste")
			(net "HSC_MODE_2")
		)
	)
	(footprint ""
		(layer "F.Cu")
		(at 297.486324 -112.354614 180)
		(property "Reference" "R2985"
			(at 0 0 180)
			(layer "F.SilkS")
			(hide yes)
			(effects
				(font
					(size 1.27 1.27)
				)
			)
		)
		(property "Value" ""
			(at 0 0 180)
			(layer "F.Fab")
			(effects
				(font
					(size 1.27 1.27)
				)
			)
		)
		(duplicate_pad_numbers_are_jumpers no)
		(fp_line
			(start 0.7874 0.4064)
			(end -0.7874 0.4064)
			(stroke
				(width 0.1524)
				(type default)
			)
			(layer "F.SilkS")
		)
		(fp_line
			(start 0.7874 -0.4064)
			(end 0.7874 0.4064)
			(stroke
				(width 0.1524)
				(type default)
			)
			(layer "F.SilkS")
		)
		(fp_line
			(start -0.7874 0.4064)
			(end -0.7874 -0.4064)
			(stroke
				(width 0.1524)
				(type default)
			)
			(layer "F.SilkS")
		)
		(fp_line
			(start -0.7874 -0.4064)
			(end 0.7874 -0.4064)
			(stroke
				(width 0.1524)
				(type default)
			)
			(layer "F.SilkS")
		)
		(fp_line
			(start 0.67945 0.3048)
			(end 0.120396 0.3048)
			(stroke
				(width 0.1)
				(type default)
			)
			(layer "F.Fab")
		)
		(fp_line
			(start 0.67945 -0.3048)
			(end 0.67945 0.3048)
			(stroke
				(width 0.1)
				(type default)
			)
			(layer "F.Fab")
		)
		(fp_line
			(start 0.12065 -0.2794)
			(end 0.12065 -0.3048)
			(stroke
				(width 0.1)
				(type default)
			)
			(layer "F.Fab")
		)
		(fp_line
			(start 0.12065 -0.3048)
			(end 0.67945 -0.3048)
			(stroke
				(width 0.1)
				(type default)
			)
			(layer "F.Fab")
		)
		(fp_line
			(start 0.120396 0.3048)
			(end 0.120396 0.2794)
			(stroke
				(width 0.1)
				(type default)
			)
			(layer "F.Fab")
		)
		(fp_line
			(start 0.120396 0.2794)
			(end -0.12065 0.2794)
			(stroke
				(width 0.1)
				(type default)
			)
			(layer "F.Fab")
		)
		(fp_line
			(start -0.12065 0.3048)
			(end -0.67945 0.3048)
			(stroke
				(width 0.1)
				(type default)
			)
			(layer "F.Fab")
		)
		(fp_line
			(start -0.12065 0.2794)
			(end -0.12065 0.3048)
			(stroke
				(width 0.1)
				(type default)
			)
			(layer "F.Fab")
		)
		(fp_line
			(start -0.12065 -0.2794)
			(end 0.12065 -0.2794)
			(stroke
				(width 0.1)
				(type default)
			)
			(layer "F.Fab")
		)
		(fp_line
			(start -0.12065 -0.305054)
			(end -0.12065 -0.2794)
			(stroke
				(width 0.1)
				(type default)
			)
			(layer "F.Fab")
		)
		(fp_line
			(start -0.67945 0.3048)
			(end -0.67945 -0.305054)
			(stroke
				(width 0.1)
				(type default)
			)
			(layer "F.Fab")
		)
		(fp_line
			(start -0.67945 -0.305054)
			(end -0.12065 -0.305054)
			(stroke
				(width 0.1)
				(type default)
			)
			(layer "F.Fab")
		)
		(pad "1" smd circle
			(at -0.40005 0 180)
			(size 0 0)
			(layers "F.Cu" "F.Mask" "F.Paste")
			(net "P3V3_AUX")
		)
		(pad "2" smd circle
			(at 0.40005 0 180)
			(size 0 0)
			(layers "F.Cu" "F.Mask" "F.Paste")
			(net "SMB_BMC_SWB_SDA")
		)
	)
)
